#ISCELL
  mstr_misc dns *
  *
#ISCELL
  pure_quanta quanta_title_block_c *
  *
#CELL
  pure_quanta q_res *
  page140_i121
#ISCELL
  logical_power universal_gnd *
  page140_i122
#ISCELL
  logical_power universal_gnd *
  page140_i125
#CELL
  pure_quanta 74lvc2g17gw *
  page140_i127
#ISCELL
  standard offpage *
  page140_i129
#ISCELL
  logical_power universal_gnd *
  page140_i132
#ISCELL
  logical_power universal_power *
  page140_i139
#CELL
  pure_quanta q_cap *
  page140_i140
#ISCELL
  logical_power universal_gnd *
  page140_i141
#ISCELL
  logical_power universal_gnd *
  page140_i142
#ISCELL
  standard offpage *
  page140_i146
#CELL
  pure_quanta q_res *
  page140_i147
#ISCELL
  logical_power universal_power *
  page140_i148
#CELL
  pure_quanta q_res *
  page140_i153
#ISCELL
  logical_power universal_gnd *
  page140_i159
#CELL
  pure_quanta q_res *
  page140_i160
#ISCELL
  logical_power universal_power *
  page140_i161
#CELL
  pure_quanta q_res *
  page140_i162
#ISCELL
  logical_power universal_power *
  page140_i165
#CELL
  pure_quanta q_cap *
  page140_i166
#ISCELL
  logical_power universal_gnd *
  page140_i167
#CELL
  pure_quanta q_res *
  page140_i170
#ISCELL
  standard offpage *
  page140_i172
#ISCELL
  standard offpage *
  page140_i173
#ISCELL
  logical_power universal_power *
  page140_i174
#ISCELL
  standard offpage *
  page140_i177
#ISCELL
  logical_power universal_gnd *
  page140_i178
#ISCELL
  standard offpage *
  page140_i180
#ISCELL
  logical_power universal_power *
  page140_i183
#ISCELL
  logical_power universal_gnd *
  page140_i184
#CELL
  pure_quanta q_res *
  page140_i190
#CELL
  pure_quanta q_res *
  page140_i191
#CELL
  pure_quanta q_res *
  page140_i192
#CELL
  pure_quanta q_res *
  page140_i193
#CELL
  pure_quanta q_res *
  page140_i194
#CELL
  pure_quanta 74lvc1g126se7 *
  page140_i195
#ISCELL
  logical_power universal_gnd *
  page140_i196
#CELL
  pure_quanta q_res *
  page140_i197
#CELL
  pure_quanta q_res *
  page140_i198
#ISCELL
  logical_power universal_power *
  page140_i199
#CELL
  pure_quanta q_res *
  page140_i200
#ISCELL
  logical_power universal_power *
  page140_i201
#CELL
  pure_quanta q_res *
  page140_i202
#CELL
  pure_quanta q_res *
  page140_i203
#CELL
  pure_quanta q_res *
  page140_i204
#CELL
  pure_quanta q_res *
  page140_i205
#CELL
  pure_quanta q_res *
  page140_i206
#CELL
  pure_quanta q_res *
  page140_i207
#CELL
  pure_quanta q_res *
  page140_i208
#ISCELL
  standard offpage *
  page140_i209
#CELL
  pure_quanta 74lvc2g17gw *
  page140_i65
#ISCELL
  logical_power universal_power *
  page140_i67
#CELL
  pure_quanta q_res *
  page140_i68
#ISCELL
  logical_power universal_gnd *
  page140_i69
#ISCELL
  standard offpage *
  page140_i70
#ISCELL
  logical_power universal_power *
  page140_i71
#ISCELL
  logical_power universal_gnd *
  page140_i74
#ISCELL
  standard offpage *
  page140_i75
#ISCELL
  logical_power universal_gnd *
  page140_i76
#CELL
  pure_quanta q_res *
  page140_i78
#ISCELL
  standard offpage *
  page140_i79
#ISCELL
  logical_power universal_power *
  page140_i80
#ISCELL
  standard offpage *
  page140_i82
#ISCELL
  logical_power universal_power *
  page140_i83
#ISCELL
  logical_power universal_power *
  page140_i87
#ISCELL
  logical_power universal_gnd *
  page140_i88
#CELL
  pure_quanta q_cap *
  page140_i89
#CELL
  pure_quanta q_res *
  page140_i92
#CELL
  pure_quanta q_res *
  page140_i93
